(kicad_pcb
	(version 20260206)
	(generator "pcbnew")
	(generator_version "10.0")
	(general
		(thickness 1.6)
		(legacy_teardrops no)
	)
	(paper "A4")
	(title_block
		(title "Wiwynn_Tioga_Pass_MB.brd")
		(comment 1 "Tioga Pass / footprints 198-205 of 4770")
	)
	(layers
		(0 "F.Cu" signal "TOP")
		(4 "In1.Cu" signal "L2GND")
		(6 "In2.Cu" signal "L3")
		(8 "In3.Cu" signal "L4GND")
		(10 "In4.Cu" signal "L5")
		(12 "In5.Cu" signal "L6GND")
		(14 "In6.Cu" signal "L7VCC")
		(16 "In7.Cu" signal "L8VCC")
		(18 "In8.Cu" signal "L9GND")
		(20 "In9.Cu" signal "L10")
		(22 "In10.Cu" signal "L11GND")
		(24 "In11.Cu" signal "L12")
		(26 "In12.Cu" signal "L13GND")
		(2 "B.Cu" signal "BOTTOM")
		(9 "F.Adhes" user "F.Adhesive")
		(11 "B.Adhes" user "B.Adhesive")
		(13 "F.Paste" user "Package Geometry/Pastemask Top")
		(15 "B.Paste" user "Package Geometry/Pastemask Bottom")
		(5 "F.SilkS" user "Ref Des/Silkscreen Top")
		(7 "B.SilkS" user "Ref Des/Silkscreen Bottom")
		(1 "F.Mask" user "Board Geometry/Soldermask Top")
		(3 "B.Mask" user "Board Geometry/Soldermask Bottom")
		(17 "Dwgs.User" user "User.Drawings")
		(19 "Cmts.User" user "User.Comments")
		(21 "Eco1.User" user "User.Eco1")
		(23 "Eco2.User" user "User.Eco2")
		(25 "Edge.Cuts" user "Board Geometry/Outline")
		(27 "Margin" user)
		(31 "F.CrtYd" user "Package Geometry/Place Bound Top")
		(29 "B.CrtYd" user "Package Geometry/Place Bound Bottom")
		(35 "F.Fab" user "Ref Des/Assembly Top")
		(33 "B.Fab" user "Ref Des/Assembly Bottom")
	)
	(footprint ""
		(layer "F.Cu")
		(at 337.404202 -121.282968 -90)
		(property "Reference" "C834"
			(at -0.8382 -0.67818 270)
			(unlocked yes)
			(layer "F.SilkS")
			(effects
				(font
					(size 0.4064 0.254)
					(thickness 0.1524)
				)
				(justify left)
			)
		)
		(property "Value" ""
			(at 0 0 270)
			(layer "F.Fab")
			(effects
				(font
					(size 1.27 1.27)
				)
			)
		)
		(duplicate_pad_numbers_are_jumpers no)
		(fp_poly
			(pts
				(xy 0.3048 -0.1016) (xy 0.3048 0.9906) (xy -0.3048 0.9906) (xy -0.3048 -0.1016)
			)
			(stroke
				(width 0)
				(type default)
			)
			(fill no)
			(layer "F.CrtYd")
		)
		(fp_line
			(start -0.3048 0.9906)
			(end 0.3048 0.9906)
			(stroke
				(width 0.1)
				(type default)
			)
			(layer "F.Fab")
		)
		(fp_line
			(start 0.3048 0.9906)
			(end 0.3048 -0.1016)
			(stroke
				(width 0.1)
				(type default)
			)
			(layer "F.Fab")
		)
		(fp_line
			(start -0.3048 -0.1016)
			(end -0.3048 0.9906)
			(stroke
				(width 0.1)
				(type default)
			)
			(layer "F.Fab")
		)
		(fp_line
			(start 0.3048 -0.1016)
			(end -0.3048 -0.1016)
			(stroke
				(width 0.1)
				(type default)
			)
			(layer "F.Fab")
		)
		(pad "1" smd rect
			(at 0 0 270)
			(size 0.508 0.508)
			(layers "F.Cu" "F.Mask" "F.Paste")
			(net "P3E_CPU0_PE1_PCH_TXN<10>")
		)
		(pad "2" smd rect
			(at 0 0.889 270)
			(size 0.508 0.508)
			(layers "F.Cu" "F.Mask" "F.Paste")
			(net "P3E_CPU0_PE1_PCH_CON_TXN<10>")
		)
		(zone
			(layer "F.Cu")
			(hatch none 0.5)
			(connect_pads
				(clearance 0)
			)
			(min_thickness 0.25)
			(keepout
				(tracks not_allowed)
				(vias allowed)
				(pads allowed)
				(copperpour not_allowed)
				(footprints allowed)
			)
			(placement
				(enabled no)
				(sheetname "")
			)
			(fill
				(thermal_gap 0.5)
				(thermal_bridge_width 0.5)
				(island_removal_mode 0)
			)
			(polygon
				(pts
					(xy 336.769202 -121.536968) (xy 336.769202 -121.028968) (xy 337.150202 -121.028968) (xy 337.150202 -121.536968)
				)
			)
		)
		(zone
			(layer "F.Cu")
			(hatch none 0.5)
			(connect_pads
				(clearance 0)
			)
			(min_thickness 0.25)
			(keepout
				(tracks allowed)
				(vias not_allowed)
				(pads allowed)
				(copperpour not_allowed)
				(footprints allowed)
			)
			(placement
				(enabled no)
				(sheetname "")
			)
			(fill
				(thermal_gap 0.5)
				(thermal_bridge_width 0.5)
				(island_removal_mode 0)
			)
			(polygon
				(pts
					(xy 337.150202 -121.536968) (xy 337.150202 -121.028968) (xy 336.769202 -121.028968) (xy 336.769202 -121.536968)
				)
			)
		)
	)
	(footprint ""
		(layer "F.Cu")
		(at 103.506778 -84.890102)
		(property "Reference" "C2D1"
			(at 0 0 0)
			(layer "F.SilkS")
			(hide yes)
			(effects
				(font
					(size 1.27 1.27)
				)
			)
		)
		(property "Value" ""
			(at 0 0 0)
			(layer "F.Fab")
			(effects
				(font
					(size 1.27 1.27)
				)
			)
		)
		(duplicate_pad_numbers_are_jumpers no)
		(fp_poly
			(pts
				(xy -0.4953 -0.2032) (xy 0.4953 -0.2032) (xy 0.4953 1.6002) (xy -0.4953 1.6002)
			)
			(stroke
				(width 0)
				(type default)
			)
			(fill no)
			(layer "F.CrtYd")
		)
		(fp_line
			(start -0.4953 -0.2032)
			(end 0.4953 -0.2032)
			(stroke
				(width 0.1)
				(type default)
			)
			(layer "F.Fab")
		)
		(fp_line
			(start -0.4953 1.6002)
			(end -0.4953 -0.2032)
			(stroke
				(width 0.1)
				(type default)
			)
			(layer "F.Fab")
		)
		(fp_line
			(start 0.4953 -0.2032)
			(end 0.4953 1.6002)
			(stroke
				(width 0.1)
				(type default)
			)
			(layer "F.Fab")
		)
		(fp_line
			(start 0.4953 1.6002)
			(end -0.4953 1.6002)
			(stroke
				(width 0.1)
				(type default)
			)
			(layer "F.Fab")
		)
		(pad "1" smd rect
			(at 0 0)
			(size 0.762 0.889)
			(layers "F.Cu" "F.Mask" "F.Paste")
			(net "PVDDQ_KLM")
		)
		(pad "2" smd rect
			(at 0 1.397)
			(size 0.762 0.889)
			(layers "F.Cu" "F.Mask" "F.Paste")
			(net "GND")
		)
		(zone
			(layer "F.Cu")
			(hatch none 0.5)
			(connect_pads
				(clearance 0)
			)
			(min_thickness 0.25)
			(keepout
				(tracks not_allowed)
				(vias allowed)
				(pads allowed)
				(copperpour not_allowed)
				(footprints allowed)
			)
			(placement
				(enabled no)
				(sheetname "")
			)
			(fill
				(thermal_gap 0.5)
				(thermal_bridge_width 0.5)
				(island_removal_mode 0)
			)
			(polygon
				(pts
					(xy 103.125778 -84.445602) (xy 103.887778 -84.445602) (xy 103.887778 -83.937602) (xy 103.125778 -83.937602)
				)
			)
		)
	)
	(footprint ""
		(layer "F.Cu")
		(at 25.02408 -91.96832 180)
		(property "Reference" "CF10"
			(at 0 0 180)
			(layer "F.SilkS")
			(hide yes)
			(effects
				(font
					(size 1.27 1.27)
				)
			)
		)
		(property "Value" "*"
			(at 1.1811 -2.8194 180)
			(unlocked yes)
			(layer "F.Fab")
			(hide yes)
			(effects
				(font
					(size 1.27 1.016)
					(thickness 0.1524)
				)
			)
		)
		(property "Device Type" "SC22P50V2JN-4GP_SMD-BCG-SC22P5A"
			(at 1.1811 -4.3434 180)
			(unlocked yes)
			(layer "F.Fab")
			(hide yes)
			(effects
				(font
					(size 1.27 1.016)
					(thickness 0.1524)
				)
			)
		)
		(duplicate_pad_numbers_are_jumpers no)
		(fp_rect
			(start -0.4318 0.9525)
			(end 0.4318 -0.9525)
			(stroke
				(width 0)
				(type default)
			)
			(fill no)
			(layer "F.CrtYd")
		)
		(fp_rect
			(start -0.4318 0.9525)
			(end 0.4318 -0.9525)
			(stroke
				(width 0)
				(type default)
			)
			(fill no)
			(layer "F.Fab")
		)
		(pad "1" smd custom
			(at 0 -0.4445 180)
			(size 0.1524 0.1524)
			(layers "F.Cu" "F.Mask" "F.Paste")
			(net "VR_PVCCIN_CPU1_AIREF4")
			(options
				(clearance outline)
				(anchor circle)
			)
			(primitives
				(gr_poly
					(pts
						(arc
							(start 0.3048 -0.2032)
							(mid 0.275042 -0.275042)
							(end 0.2032 -0.3048)
						)
						(arc
							(start -0.2032 -0.3048)
							(mid -0.275042 -0.275042)
							(end -0.3048 -0.2032)
						)
						(arc
							(start -0.3048 0.2032)
							(mid -0.275042 0.275042)
							(end -0.2032 0.3048)
						)
						(arc
							(start 0.2032 0.3048)
							(mid 0.275042 0.275042)
							(end 0.3048 0.2032)
						)
					)
					(width 0)
					(fill yes)
				)
			)
		)
		(pad "2" smd custom
			(at 0 0.4445 180)
			(size 0.1524 0.1524)
			(layers "F.Cu" "F.Mask" "F.Paste")
			(net "ISENSE_PVCCIN_CPU1_PH4_IMON")
			(options
				(clearance outline)
				(anchor circle)
			)
			(primitives
				(gr_poly
					(pts
						(arc
							(start 0.3048 -0.2032)
							(mid 0.275042 -0.275042)
							(end 0.2032 -0.3048)
						)
						(arc
							(start -0.2032 -0.3048)
							(mid -0.275042 -0.275042)
							(end -0.3048 -0.2032)
						)
						(arc
							(start -0.3048 0.2032)
							(mid -0.275042 0.275042)
							(end -0.2032 0.3048)
						)
						(arc
							(start 0.2032 0.3048)
							(mid 0.275042 0.275042)
							(end 0.3048 0.2032)
						)
					)
					(width 0)
					(fill yes)
				)
			)
		)
	)
	(footprint ""
		(layer "F.Cu")
		(at 193.8782 -91.3892 90)
		(property "Reference" "C4C17"
			(at 0 0 90)
			(layer "F.SilkS")
			(hide yes)
			(effects
				(font
					(size 1.27 1.27)
				)
			)
		)
		(property "Value" ""
			(at 0 0 90)
			(layer "F.Fab")
			(effects
				(font
					(size 1.27 1.27)
				)
			)
		)
		(duplicate_pad_numbers_are_jumpers no)
		(fp_rect
			(start -0.3048 0.9906)
			(end 0.3048 -0.1016)
			(stroke
				(width 0)
				(type default)
			)
			(fill no)
			(layer "F.CrtYd")
		)
		(fp_line
			(start 0.3048 -0.1016)
			(end -0.3048 -0.1016)
			(stroke
				(width 0.1)
				(type default)
			)
			(layer "F.Fab")
		)
		(fp_line
			(start -0.3048 -0.1016)
			(end -0.3048 0.9906)
			(stroke
				(width 0.1)
				(type default)
			)
			(layer "F.Fab")
		)
		(fp_line
			(start 0.3048 0.9906)
			(end 0.3048 -0.1016)
			(stroke
				(width 0.1)
				(type default)
			)
			(layer "F.Fab")
		)
		(fp_line
			(start -0.3048 0.9906)
			(end 0.3048 0.9906)
			(stroke
				(width 0.1)
				(type default)
			)
			(layer "F.Fab")
		)
		(pad "1" smd rect
			(at 0 0 90)
			(size 0.508 0.508)
			(layers "F.Cu" "F.Mask" "F.Paste")
			(net "VR_PVCCIN_CPU0_PH5_BOOT")
		)
		(pad "2" smd rect
			(at 0 0.889 90)
			(size 0.508 0.508)
			(layers "F.Cu" "F.Mask" "F.Paste")
			(net "VR_PVCCIN_CPU0_PH5_PHASE")
		)
		(zone
			(layer "F.Cu")
			(hatch none 0.5)
			(connect_pads
				(clearance 0)
			)
			(min_thickness 0.25)
			(keepout
				(tracks allowed)
				(vias not_allowed)
				(pads allowed)
				(copperpour not_allowed)
				(footprints allowed)
			)
			(placement
				(enabled no)
				(sheetname "")
			)
			(fill
				(thermal_gap 0.5)
				(thermal_bridge_width 0.5)
				(island_removal_mode 0)
			)
			(polygon
				(pts
					(xy 194.5132 -91.1352) (xy 194.5132 -91.6432) (xy 194.1322 -91.6432) (xy 194.1322 -91.1352)
				)
			)
		)
		(zone
			(layer "F.Cu")
			(hatch none 0.5)
			(connect_pads
				(clearance 0)
			)
			(min_thickness 0.25)
			(keepout
				(tracks not_allowed)
				(vias allowed)
				(pads allowed)
				(copperpour not_allowed)
				(footprints allowed)
			)
			(placement
				(enabled no)
				(sheetname "")
			)
			(fill
				(thermal_gap 0.5)
				(thermal_bridge_width 0.5)
				(island_removal_mode 0)
			)
			(polygon
				(pts
					(xy 194.5132 -91.1352) (xy 194.5132 -91.6432) (xy 194.1322 -91.6432) (xy 194.1322 -91.1352)
				)
			)
		)
	)
	(footprint ""
		(layer "F.Cu")
		(at 24.03602 -91.36888 180)
		(property "Reference" "RF10"
			(at -0.8382 -0.67818 180)
			(unlocked yes)
			(layer "F.SilkS")
			(effects
				(font
					(size 0.4064 0.254)
					(thickness 0.1524)
				)
				(justify left)
			)
		)
		(property "Value" ""
			(at 0 0 180)
			(layer "F.Fab")
			(effects
				(font
					(size 1.27 1.27)
				)
			)
		)
		(duplicate_pad_numbers_are_jumpers no)
		(fp_poly
			(pts
				(xy -0.2794 -0.1016) (xy 0.2794 -0.1016) (xy 0.2794 0.9906) (xy -0.2794 0.9906)
			)
			(stroke
				(width 0)
				(type default)
			)
			(fill no)
			(layer "F.CrtYd")
		)
		(fp_line
			(start 0.2794 0.9906)
			(end 0.2794 -0.1016)
			(stroke
				(width 0.1)
				(type default)
			)
			(layer "F.Fab")
		)
		(fp_line
			(start 0.2794 -0.1016)
			(end -0.2794 -0.1016)
			(stroke
				(width 0.1)
				(type default)
			)
			(layer "F.Fab")
		)
		(fp_line
			(start -0.2794 0.9906)
			(end 0.2794 0.9906)
			(stroke
				(width 0.1)
				(type default)
			)
			(layer "F.Fab")
		)
		(fp_line
			(start -0.2794 -0.1016)
			(end -0.2794 0.9906)
			(stroke
				(width 0.1)
				(type default)
			)
			(layer "F.Fab")
		)
		(pad "1" smd rect
			(at 0 0 180)
			(size 0.508 0.508)
			(layers "F.Cu" "F.Mask" "F.Paste")
			(net "VR_PVCCIN_CPU1_AIREF4")
		)
		(pad "2" smd rect
			(at 0 0.889 180)
			(size 0.508 0.508)
			(layers "F.Cu" "F.Mask" "F.Paste")
			(net "ISENSE_PVCCIN_CPU1_PH4_IMON")
		)
		(zone
			(layer "F.Cu")
			(hatch none 0.5)
			(connect_pads
				(clearance 0)
			)
			(min_thickness 0.25)
			(keepout
				(tracks not_allowed)
				(vias allowed)
				(pads allowed)
				(copperpour not_allowed)
				(footprints allowed)
			)
			(placement
				(enabled no)
				(sheetname "")
			)
			(fill
				(thermal_gap 0.5)
				(thermal_bridge_width 0.5)
				(island_removal_mode 0)
			)
			(polygon
				(pts
					(xy 24.29002 -92.00388) (xy 23.78202 -92.00388) (xy 23.78202 -91.62288) (xy 24.29002 -91.62288)
				)
			)
		)
		(zone
			(layer "F.Cu")
			(hatch none 0.5)
			(connect_pads
				(clearance 0)
			)
			(min_thickness 0.25)
			(keepout
				(tracks allowed)
				(vias not_allowed)
				(pads allowed)
				(copperpour not_allowed)
				(footprints allowed)
			)
			(placement
				(enabled no)
				(sheetname "")
			)
			(fill
				(thermal_gap 0.5)
				(thermal_bridge_width 0.5)
				(island_removal_mode 0)
			)
			(polygon
				(pts
					(xy 24.29002 -91.62288) (xy 23.78202 -91.62288) (xy 23.78202 -92.00388) (xy 24.29002 -92.00388)
				)
			)
		)
	)
	(footprint ""
		(layer "F.Cu")
		(at 17.5768 -43.6626 90)
		(property "Reference" "R1E11"
			(at 0 0 90)
			(layer "F.SilkS")
			(hide yes)
			(effects
				(font
					(size 1.27 1.27)
				)
			)
		)
		(property "Value" ""
			(at 0 0 90)
			(layer "F.Fab")
			(effects
				(font
					(size 1.27 1.27)
				)
			)
		)
		(duplicate_pad_numbers_are_jumpers no)
		(fp_rect
			(start 0.2794 -0.1016)
			(end -0.2794 0.9906)
			(stroke
				(width 0)
				(type default)
			)
			(fill no)
			(layer "F.CrtYd")
		)
		(fp_line
			(start 0.2794 -0.1016)
			(end -0.2794 -0.1016)
			(stroke
				(width 0.1)
				(type default)
			)
			(layer "F.Fab")
		)
		(fp_line
			(start -0.2794 -0.1016)
			(end -0.2794 0.9906)
			(stroke
				(width 0.1)
				(type default)
			)
			(layer "F.Fab")
		)
		(fp_line
			(start 0.2794 0.9906)
			(end 0.2794 -0.1016)
			(stroke
				(width 0.1)
				(type default)
			)
			(layer "F.Fab")
		)
		(fp_line
			(start -0.2794 0.9906)
			(end 0.2794 0.9906)
			(stroke
				(width 0.1)
				(type default)
			)
			(layer "F.Fab")
		)
		(pad "1" smd rect
			(at 0 0 90)
			(size 0.508 0.508)
			(layers "F.Cu" "F.Mask" "F.Paste")
			(net "P3V3_STBY")
		)
		(pad "2" smd rect
			(at 0 0.889 90)
			(size 0.508 0.508)
			(layers "F.Cu" "F.Mask" "F.Paste")
			(net "FM_ENABLE_FAN_POWER")
		)
		(zone
			(layer "F.Cu")
			(hatch none 0.5)
			(connect_pads
				(clearance 0)
			)
			(min_thickness 0.25)
			(keepout
				(tracks allowed)
				(vias not_allowed)
				(pads allowed)
				(copperpour not_allowed)
				(footprints allowed)
			)
			(placement
				(enabled no)
				(sheetname "")
			)
			(fill
				(thermal_gap 0.5)
				(thermal_bridge_width 0.5)
				(island_removal_mode 0)
			)
			(polygon
				(pts
					(xy 17.8308 -43.9166) (xy 17.8308 -43.4086) (xy 18.2118 -43.4086) (xy 18.2118 -43.9166)
				)
			)
		)
		(zone
			(layer "F.Cu")
			(hatch none 0.5)
			(connect_pads
				(clearance 0)
			)
			(min_thickness 0.25)
			(keepout
				(tracks not_allowed)
				(vias allowed)
				(pads allowed)
				(copperpour not_allowed)
				(footprints allowed)
			)
			(placement
				(enabled no)
				(sheetname "")
			)
			(fill
				(thermal_gap 0.5)
				(thermal_bridge_width 0.5)
				(island_removal_mode 0)
			)
			(polygon
				(pts
					(xy 17.8308 -43.9166) (xy 17.8308 -43.4086) (xy 18.2118 -43.4086) (xy 18.2118 -43.9166)
				)
			)
		)
	)
	(footprint ""
		(layer "F.Cu")
		(at 181.763924 -153.6827 90)
		(property "Reference" "C4A1"
			(at 0 0 90)
			(layer "F.SilkS")
			(hide yes)
			(effects
				(font
					(size 1.27 1.27)
				)
			)
		)
		(property "Value" ""
			(at 0 0 90)
			(layer "F.Fab")
			(effects
				(font
					(size 1.27 1.27)
				)
			)
		)
		(duplicate_pad_numbers_are_jumpers no)
		(fp_rect
			(start 0.7239 1.9939)
			(end -0.7239 -0.2159)
			(stroke
				(width 0)
				(type default)
			)
			(fill no)
			(layer "F.CrtYd")
		)
		(fp_line
			(start 0.7239 -0.2159)
			(end -0.7239 -0.2159)
			(stroke
				(width 0.1)
				(type default)
			)
			(layer "F.Fab")
		)
		(fp_line
			(start -0.7239 -0.2159)
			(end -0.7239 1.9939)
			(stroke
				(width 0.1)
				(type default)
			)
			(layer "F.Fab")
		)
		(fp_line
			(start 0.7239 1.9939)
			(end 0.7239 -0.2159)
			(stroke
				(width 0.1)
				(type default)
			)
			(layer "F.Fab")
		)
		(fp_line
			(start -0.7239 1.9939)
			(end 0.7239 1.9939)
			(stroke
				(width 0.1)
				(type default)
			)
			(layer "F.Fab")
		)
		(pad "1" smd rect
			(at 0 0 90)
			(size 1.27 1.016)
			(layers "F.Cu" "F.Mask" "F.Paste")
			(net "PVTT_DEF")
		)
		(pad "2" smd rect
			(at 0 1.778 90)
			(size 1.27 1.016)
			(layers "F.Cu" "F.Mask" "F.Paste")
			(net "GND")
		)
		(zone
			(layer "F.Cu")
			(hatch none 0.5)
			(connect_pads
				(clearance 0)
			)
			(min_thickness 0.25)
			(keepout
				(tracks not_allowed)
				(vias allowed)
				(pads allowed)
				(copperpour not_allowed)
				(footprints allowed)
			)
			(placement
				(enabled no)
				(sheetname "")
			)
			(fill
				(thermal_gap 0.5)
				(thermal_bridge_width 0.5)
				(island_removal_mode 0)
			)
			(polygon
				(pts
					(xy 183.033924 -154.3177) (xy 182.271924 -154.3177) (xy 182.271924 -153.0477) (xy 183.033924 -153.0477)
				)
			)
		)
	)
	(footprint ""
		(layer "F.Cu")
		(at 402.66874 -33.664652 -90)
		(property "Reference" "R2U34"
			(at 0 0 270)
			(layer "F.SilkS")
			(hide yes)
			(effects
				(font
					(size 1.27 1.27)
				)
			)
		)
		(property "Value" ""
			(at 0 0 270)
			(layer "F.Fab")
			(effects
				(font
					(size 1.27 1.27)
				)
			)
		)
		(duplicate_pad_numbers_are_jumpers no)
		(fp_poly
			(pts
				(xy -0.2794 -0.1016) (xy 0.2794 -0.1016) (xy 0.2794 0.9906) (xy -0.2794 0.9906)
			)
			(stroke
				(width 0)
				(type default)
			)
			(fill no)
			(layer "F.CrtYd")
		)
		(fp_line
			(start -0.2794 0.9906)
			(end 0.2794 0.9906)
			(stroke
				(width 0.1)
				(type default)
			)
			(layer "F.Fab")
		)
		(fp_line
			(start 0.2794 0.9906)
			(end 0.2794 -0.1016)
			(stroke
				(width 0.1)
				(type default)
			)
			(layer "F.Fab")
		)
		(fp_line
			(start -0.2794 -0.1016)
			(end -0.2794 0.9906)
			(stroke
				(width 0.1)
				(type default)
			)
			(layer "F.Fab")
		)
		(fp_line
			(start 0.2794 -0.1016)
			(end -0.2794 -0.1016)
			(stroke
				(width 0.1)
				(type default)
			)
			(layer "F.Fab")
		)
		(pad "1" smd rect
			(at 0 0 270)
			(size 0.508 0.508)
			(layers "F.Cu" "F.Mask" "F.Paste")
			(net "SMB_HOST_STBY_LVC3_SCL_R")
		)
		(pad "2" smd rect
			(at 0 0.889 270)
			(size 0.508 0.508)
			(layers "F.Cu" "F.Mask" "F.Paste")
			(net "SMB_HOST_STBY_LVC3_SCL")
		)
		(zone
			(layer "F.Cu")
			(hatch none 0.5)
			(connect_pads
				(clearance 0)
			)
			(min_thickness 0.25)
			(keepout
				(tracks not_allowed)
				(vias allowed)
				(pads allowed)
				(copperpour not_allowed)
				(footprints allowed)
			)
			(placement
				(enabled no)
				(sheetname "")
			)
			(fill
				(thermal_gap 0.5)
				(thermal_bridge_width 0.5)
				(island_removal_mode 0)
			)
			(polygon
				(pts
					(xy 402.03374 -33.918652) (xy 402.03374 -33.410652) (xy 402.41474 -33.410652) (xy 402.41474 -33.918652)
				)
			)
		)
		(zone
			(layer "F.Cu")
			(hatch none 0.5)
			(connect_pads
				(clearance 0)
			)
			(min_thickness 0.25)
			(keepout
				(tracks allowed)
				(vias not_allowed)
				(pads allowed)
				(copperpour not_allowed)
				(footprints allowed)
			)
			(placement
				(enabled no)
				(sheetname "")
			)
			(fill
				(thermal_gap 0.5)
				(thermal_bridge_width 0.5)
				(island_removal_mode 0)
			)
			(polygon
				(pts
					(xy 402.41474 -33.918652) (xy 402.41474 -33.410652) (xy 402.03374 -33.410652) (xy 402.03374 -33.918652)
				)
			)
		)
	)
)
